(kicad_pcb
	(version 20260206)
	(generator "pcbnew")
	(generator_version "10.0")
	(general
		(thickness 1.6)
		(legacy_teardrops no)
	)
	(paper "A4")
	(title_block
		(title "v1-chassis-manager — T6M_CM_d_v01_1031_1645.brd")
		(comment 1 "Open CloudServer (Microsoft) / footprints 1171-1180 of 2512")
	)
	(layers
		(0 "F.Cu" signal "TOP")
		(4 "In1.Cu" signal "GND1")
		(6 "In2.Cu" signal "IN1")
		(8 "In3.Cu" signal "VCC1")
		(10 "In4.Cu" signal "VCC2")
		(12 "In5.Cu" signal "GND2")
		(14 "In6.Cu" signal "IN2")
		(16 "In7.Cu" signal "IN3")
		(18 "In8.Cu" signal "GND3")
		(2 "B.Cu" signal "BOTTOM")
		(9 "F.Adhes" user "F.Adhesive")
		(11 "B.Adhes" user "B.Adhesive")
		(13 "F.Paste" user "Package Geometry/Pastemask Top")
		(15 "B.Paste" user "Package Geometry/Pastemask Bottom")
		(5 "F.SilkS" user "Ref Des/Silkscreen Top")
		(7 "B.SilkS" user "Ref Des/Silkscreen Bottom")
		(1 "F.Mask" user "Board Geometry/Soldermask Top")
		(3 "B.Mask" user "Board Geometry/Soldermask Bottom")
		(17 "Dwgs.User" user "User.Drawings")
		(19 "Cmts.User" user "User.Comments")
		(21 "Eco1.User" user "User.Eco1")
		(23 "Eco2.User" user "User.Eco2")
		(25 "Edge.Cuts" user "Board Geometry/Outline")
		(27 "Margin" user)
		(31 "F.CrtYd" user "Package Geometry/Place Bound Top")
		(29 "B.CrtYd" user "Package Geometry/Place Bound Bottom")
		(35 "F.Fab" user "Ref Des/Assembly Top")
		(33 "B.Fab" user "Ref Des/Assembly Bottom")
	)
	(footprint ""
		(layer "F.Cu")
		(at 58.216546 -161.928556 90)
		(property "Reference" "R547"
			(at -1.333754 12.174728 90)
			(unlocked yes)
			(layer "F.SilkS")
			(effects
				(font
					(size 0.7874 0.5842)
					(thickness 0.1524)
				)
				(justify left)
			)
		)
		(property "Value" ""
			(at 0 0 90)
			(layer "F.Fab")
			(effects
				(font
					(size 1.27 1.27)
				)
			)
		)
		(duplicate_pad_numbers_are_jumpers no)
		(fp_line
			(start 0.7874 -0.4064)
			(end 0.7874 0.4064)
			(stroke
				(width 0.1524)
				(type default)
			)
			(layer "F.SilkS")
		)
		(fp_line
			(start -0.7874 -0.4064)
			(end 0.7874 -0.4064)
			(stroke
				(width 0.1524)
				(type default)
			)
			(layer "F.SilkS")
		)
		(fp_line
			(start 0.7874 0.4064)
			(end -0.7874 0.4064)
			(stroke
				(width 0.1524)
				(type default)
			)
			(layer "F.SilkS")
		)
		(fp_line
			(start -0.7874 0.4064)
			(end -0.7874 -0.4064)
			(stroke
				(width 0.1524)
				(type default)
			)
			(layer "F.SilkS")
		)
		(fp_poly
			(pts
				(xy -0.508 0.2794) (xy -0.508 0.2286) (xy -0.635 0.2286) (xy -0.635 -0.254) (xy -0.5334 -0.254)
				(xy -0.5334 -0.2794) (xy 0.5334 -0.2794) (xy 0.5334 -0.254) (xy 0.635 -0.254) (xy 0.635 0.254) (xy 0.5334 0.254)
				(xy 0.5334 0.2794)
			)
			(stroke
				(width 0)
				(type default)
			)
			(fill no)
			(layer "F.CrtYd")
		)
		(pad "1" smd rect
			(at 0.40005 0 90)
			(size 0.4572 0.508)
			(layers "F.Cu" "F.Mask" "F.Paste")
			(net "SPI_LAN1_NVM_SI")
		)
		(pad "2" smd rect
			(at -0.40005 0 90)
			(size 0.4572 0.508)
			(layers "F.Cu" "F.Mask" "F.Paste")
			(net "LAN1_NVM_SI_R")
		)
	)
	(footprint ""
		(layer "F.Cu")
		(at 128.25857 -26.569416 -90)
		(property "Reference" "R1142"
			(at 5.325618 -0.028448 90)
			(unlocked yes)
			(layer "F.SilkS")
			(effects
				(font
					(size 0.7874 0.5842)
					(thickness 0.1524)
				)
				(justify left)
			)
		)
		(property "Value" ""
			(at 0 0 270)
			(layer "F.Fab")
			(effects
				(font
					(size 1.27 1.27)
				)
			)
		)
		(duplicate_pad_numbers_are_jumpers no)
		(fp_line
			(start -0.7874 0.4064)
			(end -0.7874 -0.4064)
			(stroke
				(width 0.1524)
				(type default)
			)
			(layer "F.SilkS")
		)
		(fp_line
			(start 0.7874 0.4064)
			(end -0.7874 0.4064)
			(stroke
				(width 0.1524)
				(type default)
			)
			(layer "F.SilkS")
		)
		(fp_line
			(start -0.7874 -0.4064)
			(end 0.7874 -0.4064)
			(stroke
				(width 0.1524)
				(type default)
			)
			(layer "F.SilkS")
		)
		(fp_line
			(start 0.7874 -0.4064)
			(end 0.7874 0.4064)
			(stroke
				(width 0.1524)
				(type default)
			)
			(layer "F.SilkS")
		)
		(fp_poly
			(pts
				(xy -0.508 0.2794) (xy -0.508 0.2286) (xy -0.635 0.2286) (xy -0.635 -0.254) (xy -0.5334 -0.254)
				(xy -0.5334 -0.2794) (xy 0.5334 -0.2794) (xy 0.5334 -0.254) (xy 0.635 -0.254) (xy 0.635 0.254) (xy 0.5334 0.254)
				(xy 0.5334 0.2794)
			)
			(stroke
				(width 0)
				(type default)
			)
			(fill no)
			(layer "F.CrtYd")
		)
		(pad "1" smd rect
			(at 0.40005 0 270)
			(size 0.4572 0.508)
			(layers "F.Cu" "F.Mask" "F.Paste")
			(net "P3V3_STB_NODE1")
		)
		(pad "2" smd rect
			(at -0.40005 0 270)
			(size 0.4572 0.508)
			(layers "F.Cu" "F.Mask" "F.Paste")
			(net "SIO_PIN75")
		)
	)
	(footprint ""
		(layer "F.Cu")
		(at 166.70782 -123.76531 180)
		(property "Reference" "R1031"
			(at 2.79019 -9.851644 0)
			(unlocked yes)
			(layer "F.SilkS")
			(effects
				(font
					(size 0.7874 0.5842)
					(thickness 0.1524)
				)
				(justify left)
			)
		)
		(property "Value" ""
			(at 0 0 180)
			(layer "F.Fab")
			(effects
				(font
					(size 1.27 1.27)
				)
			)
		)
		(duplicate_pad_numbers_are_jumpers no)
		(fp_line
			(start 0.7874 0.4064)
			(end -0.7874 0.4064)
			(stroke
				(width 0.1524)
				(type default)
			)
			(layer "F.SilkS")
		)
		(fp_line
			(start 0.7874 -0.4064)
			(end 0.7874 0.4064)
			(stroke
				(width 0.1524)
				(type default)
			)
			(layer "F.SilkS")
		)
		(fp_line
			(start -0.7874 0.4064)
			(end -0.7874 -0.4064)
			(stroke
				(width 0.1524)
				(type default)
			)
			(layer "F.SilkS")
		)
		(fp_line
			(start -0.7874 -0.4064)
			(end 0.7874 -0.4064)
			(stroke
				(width 0.1524)
				(type default)
			)
			(layer "F.SilkS")
		)
		(fp_poly
			(pts
				(xy -0.508 0.2794) (xy -0.508 0.2286) (xy -0.635 0.2286) (xy -0.635 -0.254) (xy -0.5334 -0.254)
				(xy -0.5334 -0.2794) (xy 0.5334 -0.2794) (xy 0.5334 -0.254) (xy 0.635 -0.254) (xy 0.635 0.254) (xy 0.5334 0.254)
				(xy 0.5334 0.2794)
			)
			(stroke
				(width 0)
				(type default)
			)
			(fill no)
			(layer "F.CrtYd")
		)
		(pad "1" smd rect
			(at 0.40005 0 180)
			(size 0.4572 0.508)
			(layers "F.Cu" "F.Mask" "F.Paste")
			(net "P3V3_STB_NODE1")
		)
		(pad "2" smd rect
			(at -0.40005 0 180)
			(size 0.4572 0.508)
			(layers "F.Cu" "F.Mask" "F.Paste")
			(net "LED_PWR_NODE1_L")
		)
	)
	(footprint ""
		(layer "F.Cu")
		(at 28.498546 -98.546412)
		(property "Reference" "R180"
			(at 1.778254 0.367284 0)
			(unlocked yes)
			(layer "F.SilkS")
			(effects
				(font
					(size 0.7874 0.5842)
					(thickness 0.1524)
				)
				(justify left)
			)
		)
		(property "Value" ""
			(at 0 0 0)
			(layer "F.Fab")
			(effects
				(font
					(size 1.27 1.27)
				)
			)
		)
		(duplicate_pad_numbers_are_jumpers no)
		(fp_line
			(start -0.7874 -0.4064)
			(end 0.7874 -0.4064)
			(stroke
				(width 0.1524)
				(type default)
			)
			(layer "F.SilkS")
		)
		(fp_line
			(start -0.7874 0.4064)
			(end -0.7874 -0.4064)
			(stroke
				(width 0.1524)
				(type default)
			)
			(layer "F.SilkS")
		)
		(fp_line
			(start 0.7874 -0.4064)
			(end 0.7874 0.4064)
			(stroke
				(width 0.1524)
				(type default)
			)
			(layer "F.SilkS")
		)
		(fp_line
			(start 0.7874 0.4064)
			(end -0.7874 0.4064)
			(stroke
				(width 0.1524)
				(type default)
			)
			(layer "F.SilkS")
		)
		(fp_poly
			(pts
				(xy -0.508 0.2794) (xy -0.508 0.2286) (xy -0.635 0.2286) (xy -0.635 -0.254) (xy -0.5334 -0.254)
				(xy -0.5334 -0.2794) (xy 0.5334 -0.2794) (xy 0.5334 -0.254) (xy 0.635 -0.254) (xy 0.635 0.254) (xy 0.5334 0.254)
				(xy 0.5334 0.2794)
			)
			(stroke
				(width 0)
				(type default)
			)
			(fill no)
			(layer "F.CrtYd")
		)
		(pad "1" smd rect
			(at 0.40005 0)
			(size 0.4572 0.508)
			(layers "F.Cu" "F.Mask" "F.Paste")
			(net "P3V3_NODE1")
		)
		(pad "2" smd rect
			(at -0.40005 0)
			(size 0.4572 0.508)
			(layers "F.Cu" "F.Mask" "F.Paste")
			(net "FRU_SYS_A0")
		)
	)
	(footprint ""
		(layer "F.Cu")
		(at 141.08176 -185.205624 -90)
		(property "Reference" "R873"
			(at -4.768088 0.535432 90)
			(unlocked yes)
			(layer "F.SilkS")
			(effects
				(font
					(size 0.7874 0.5842)
					(thickness 0.1524)
				)
				(justify left)
			)
		)
		(property "Value" ""
			(at 0 0 270)
			(layer "F.Fab")
			(effects
				(font
					(size 1.27 1.27)
				)
			)
		)
		(duplicate_pad_numbers_are_jumpers no)
		(fp_line
			(start -0.7874 0.4064)
			(end -0.7874 -0.4064)
			(stroke
				(width 0.1524)
				(type default)
			)
			(layer "F.SilkS")
		)
		(fp_line
			(start 0.7874 0.4064)
			(end -0.7874 0.4064)
			(stroke
				(width 0.1524)
				(type default)
			)
			(layer "F.SilkS")
		)
		(fp_line
			(start -0.7874 -0.4064)
			(end 0.7874 -0.4064)
			(stroke
				(width 0.1524)
				(type default)
			)
			(layer "F.SilkS")
		)
		(fp_line
			(start 0.7874 -0.4064)
			(end 0.7874 0.4064)
			(stroke
				(width 0.1524)
				(type default)
			)
			(layer "F.SilkS")
		)
		(fp_poly
			(pts
				(xy -0.508 0.2794) (xy -0.508 0.2286) (xy -0.635 0.2286) (xy -0.635 -0.254) (xy -0.5334 -0.254)
				(xy -0.5334 -0.2794) (xy 0.5334 -0.2794) (xy 0.5334 -0.254) (xy 0.635 -0.254) (xy 0.635 0.254) (xy 0.5334 0.254)
				(xy 0.5334 0.2794)
			)
			(stroke
				(width 0)
				(type default)
			)
			(fill no)
			(layer "F.CrtYd")
		)
		(pad "1" smd rect
			(at 0.40005 0 270)
			(size 0.4572 0.508)
			(layers "F.Cu" "F.Mask" "F.Paste")
			(net "T10_NODE1_EN")
		)
		(pad "2" smd rect
			(at -0.40005 0 270)
			(size 0.4572 0.508)
			(layers "F.Cu" "F.Mask" "F.Paste")
			(net "T10_NODE1_EN_R")
		)
	)
	(footprint ""
		(layer "F.Cu")
		(at 162.143694 -129.85242)
		(property "Reference" "D21"
			(at 2.934716 1.07442 0)
			(unlocked yes)
			(layer "F.SilkS")
			(effects
				(font
					(size 0.7874 0.5842)
					(thickness 0.1524)
				)
				(justify left)
			)
		)
		(property "Value" ""
			(at 0 0 0)
			(layer "F.Fab")
			(effects
				(font
					(size 1.27 1.27)
				)
			)
		)
		(duplicate_pad_numbers_are_jumpers no)
		(fp_line
			(start -1.3208 -0.5588)
			(end 1.3208 -0.5588)
			(stroke
				(width 0.1524)
				(type default)
			)
			(layer "F.SilkS")
		)
		(fp_line
			(start -1.3208 0.5588)
			(end -1.3208 -0.5588)
			(stroke
				(width 0.1524)
				(type default)
			)
			(layer "F.SilkS")
		)
		(fp_line
			(start 1.3208 -0.5588)
			(end 1.3208 0.5588)
			(stroke
				(width 0.1524)
				(type default)
			)
			(layer "F.SilkS")
		)
		(fp_line
			(start 1.3208 0.5588)
			(end -1.3208 0.5588)
			(stroke
				(width 0.1524)
				(type default)
			)
			(layer "F.SilkS")
		)
		(fp_line
			(start 1.4732 -0.5588)
			(end 1.4732 0.5588)
			(stroke
				(width 0.1524)
				(type default)
			)
			(layer "F.SilkS")
		)
		(fp_line
			(start 1.6256 0.5588)
			(end 1.6256 -0.5588)
			(stroke
				(width 0.1524)
				(type default)
			)
			(layer "F.SilkS")
		)
		(fp_line
			(start 1.778 -0.5588)
			(end 1.3208 -0.5588)
			(stroke
				(width 0.1524)
				(type default)
			)
			(layer "F.SilkS")
		)
		(fp_line
			(start 1.778 -0.5588)
			(end 1.778 0.5588)
			(stroke
				(width 0.1524)
				(type default)
			)
			(layer "F.SilkS")
		)
		(fp_line
			(start 1.778 0.5588)
			(end 1.3208 0.5588)
			(stroke
				(width 0.1524)
				(type default)
			)
			(layer "F.SilkS")
		)
		(fp_circle
			(center 2.50952 0.72898)
			(end 2.923032 0.72898)
			(stroke
				(width 0.1524)
				(type default)
			)
			(fill no)
			(layer "F.SilkS")
		)
		(fp_rect
			(start -1.1684 0.508)
			(end 1.1684 -0.508)
			(stroke
				(width 0)
				(type default)
			)
			(fill no)
			(layer "F.CrtYd")
		)
		(pad "A" smd rect
			(at -0.750062 0)
			(size 0.8128 0.8128)
			(layers "F.Cu" "F.Mask" "F.Paste")
			(net "LED_CPU_NODE1_CPLD_D")
		)
		(pad "C" smd rect
			(at 0.750062 0)
			(size 0.8128 0.8128)
			(layers "F.Cu" "F.Mask" "F.Paste")
			(net "LED_CPU_NODE1_CPLD")
		)
	)
	(footprint ""
		(layer "F.Cu")
		(at 60.352686 -118.910862 90)
		(property "Reference" "R317"
			(at -5.140706 0.75184 90)
			(unlocked yes)
			(layer "F.SilkS")
			(effects
				(font
					(size 0.7874 0.5842)
					(thickness 0.1524)
				)
				(justify left)
			)
		)
		(property "Value" ""
			(at 0 0 90)
			(layer "F.Fab")
			(effects
				(font
					(size 1.27 1.27)
				)
			)
		)
		(duplicate_pad_numbers_are_jumpers no)
		(fp_line
			(start 0.7874 -0.4064)
			(end 0.7874 0.4064)
			(stroke
				(width 0.1524)
				(type default)
			)
			(layer "F.SilkS")
		)
		(fp_line
			(start -0.7874 -0.4064)
			(end 0.7874 -0.4064)
			(stroke
				(width 0.1524)
				(type default)
			)
			(layer "F.SilkS")
		)
		(fp_line
			(start 0.7874 0.4064)
			(end -0.7874 0.4064)
			(stroke
				(width 0.1524)
				(type default)
			)
			(layer "F.SilkS")
		)
		(fp_line
			(start -0.7874 0.4064)
			(end -0.7874 -0.4064)
			(stroke
				(width 0.1524)
				(type default)
			)
			(layer "F.SilkS")
		)
		(fp_poly
			(pts
				(xy -0.508 0.2794) (xy -0.508 0.2286) (xy -0.635 0.2286) (xy -0.635 -0.254) (xy -0.5334 -0.254)
				(xy -0.5334 -0.2794) (xy 0.5334 -0.2794) (xy 0.5334 -0.254) (xy 0.635 -0.254) (xy 0.635 0.254) (xy 0.5334 0.254)
				(xy 0.5334 0.2794)
			)
			(stroke
				(width 0)
				(type default)
			)
			(fill no)
			(layer "F.CrtYd")
		)
		(pad "1" smd rect
			(at 0.40005 0 90)
			(size 0.4572 0.508)
			(layers "F.Cu" "F.Mask" "F.Paste")
			(net "P3V3_NODE1")
		)
		(pad "2" smd rect
			(at -0.40005 0 90)
			(size 0.4572 0.508)
			(layers "F.Cu" "F.Mask" "F.Paste")
			(net "BMC_ROMA1")
		)
	)
	(footprint ""
		(layer "F.Cu")
		(at 154.542998 -142.88643 -90)
		(property "Reference" "R592"
			(at -1.289304 -0.58801 90)
			(unlocked yes)
			(layer "F.SilkS")
			(effects
				(font
					(size 0.7874 0.5842)
					(thickness 0.1524)
				)
				(justify left)
			)
		)
		(property "Value" ""
			(at 0 0 270)
			(layer "F.Fab")
			(effects
				(font
					(size 1.27 1.27)
				)
			)
		)
		(duplicate_pad_numbers_are_jumpers no)
		(fp_line
			(start -0.7874 0.4064)
			(end -0.7874 -0.4064)
			(stroke
				(width 0.1524)
				(type default)
			)
			(layer "F.SilkS")
		)
		(fp_line
			(start 0.7874 0.4064)
			(end -0.7874 0.4064)
			(stroke
				(width 0.1524)
				(type default)
			)
			(layer "F.SilkS")
		)
		(fp_line
			(start -0.7874 -0.4064)
			(end 0.7874 -0.4064)
			(stroke
				(width 0.1524)
				(type default)
			)
			(layer "F.SilkS")
		)
		(fp_line
			(start 0.7874 -0.4064)
			(end 0.7874 0.4064)
			(stroke
				(width 0.1524)
				(type default)
			)
			(layer "F.SilkS")
		)
		(fp_poly
			(pts
				(xy -0.508 0.2794) (xy -0.508 0.2286) (xy -0.635 0.2286) (xy -0.635 -0.254) (xy -0.5334 -0.254)
				(xy -0.5334 -0.2794) (xy 0.5334 -0.2794) (xy 0.5334 -0.254) (xy 0.635 -0.254) (xy 0.635 0.254) (xy 0.5334 0.254)
				(xy 0.5334 0.2794)
			)
			(stroke
				(width 0)
				(type default)
			)
			(fill no)
			(layer "F.CrtYd")
		)
		(pad "1" smd rect
			(at 0.40005 0 270)
			(size 0.4572 0.508)
			(layers "F.Cu" "F.Mask" "F.Paste")
			(net "SMB_PCH_SDA")
		)
		(pad "2" smd rect
			(at -0.40005 0 270)
			(size 0.4572 0.508)
			(layers "F.Cu" "F.Mask" "F.Paste")
			(net "SMB_LAN2_DAT")
		)
	)
	(footprint ""
		(layer "F.Cu")
		(at 148.058632 -141.02969 180)
		(property "Reference" "R309"
			(at -1.545336 -0.942848 0)
			(unlocked yes)
			(layer "F.SilkS")
			(effects
				(font
					(size 0.635 0.4064)
					(thickness 0.1524)
				)
				(justify left)
			)
		)
		(property "Value" ""
			(at 0 0 180)
			(layer "F.Fab")
			(effects
				(font
					(size 1.27 1.27)
				)
			)
		)
		(duplicate_pad_numbers_are_jumpers no)
		(fp_line
			(start 0.7874 0.4064)
			(end -0.7874 0.4064)
			(stroke
				(width 0.1524)
				(type default)
			)
			(layer "F.SilkS")
		)
		(fp_line
			(start 0.7874 -0.4064)
			(end 0.7874 0.4064)
			(stroke
				(width 0.1524)
				(type default)
			)
			(layer "F.SilkS")
		)
		(fp_line
			(start -0.7874 0.4064)
			(end -0.7874 -0.4064)
			(stroke
				(width 0.1524)
				(type default)
			)
			(layer "F.SilkS")
		)
		(fp_line
			(start -0.7874 -0.4064)
			(end 0.7874 -0.4064)
			(stroke
				(width 0.1524)
				(type default)
			)
			(layer "F.SilkS")
		)
		(fp_poly
			(pts
				(xy -0.508 0.2794) (xy -0.508 0.2286) (xy -0.635 0.2286) (xy -0.635 -0.254) (xy -0.5334 -0.254)
				(xy -0.5334 -0.2794) (xy 0.5334 -0.2794) (xy 0.5334 -0.254) (xy 0.635 -0.254) (xy 0.635 0.254) (xy 0.5334 0.254)
				(xy 0.5334 0.2794)
			)
			(stroke
				(width 0)
				(type default)
			)
			(fill no)
			(layer "F.CrtYd")
		)
		(pad "1" smd rect
			(at 0.40005 0 180)
			(size 0.4572 0.508)
			(layers "F.Cu" "F.Mask" "F.Paste")
			(net "PCIE_SW_I2C_SCL")
		)
		(pad "2" smd rect
			(at -0.40005 0 180)
			(size 0.4572 0.508)
			(layers "F.Cu" "F.Mask" "F.Paste")
			(net "P3V3_NODE1")
		)
	)
	(footprint ""
		(layer "F.Cu")
		(at 155.989528 -133.849618 180)
		(property "Reference" "C802"
			(at 5.089652 -0.688594 0)
			(unlocked yes)
			(layer "F.SilkS")
			(effects
				(font
					(size 0.7874 0.5842)
					(thickness 0.1524)
				)
				(justify left)
			)
		)
		(property "Value" ""
			(at 0 0 180)
			(layer "F.Fab")
			(effects
				(font
					(size 1.27 1.27)
				)
			)
		)
		(duplicate_pad_numbers_are_jumpers no)
		(fp_line
			(start 1.905 0.8636)
			(end -1.905 0.8636)
			(stroke
				(width 0.1524)
				(type default)
			)
			(layer "F.SilkS")
		)
		(fp_line
			(start 1.905 -0.8636)
			(end 1.905 0.8636)
			(stroke
				(width 0.1524)
				(type default)
			)
			(layer "F.SilkS")
		)
		(fp_line
			(start 0 0.8382)
			(end 0 -0.8382)
			(stroke
				(width 0.1524)
				(type default)
			)
			(layer "F.SilkS")
		)
		(fp_line
			(start -1.905 0.8636)
			(end -1.905 -0.8636)
			(stroke
				(width 0.1524)
				(type default)
			)
			(layer "F.SilkS")
		)
		(fp_line
			(start -1.905 -0.8636)
			(end 1.905 -0.8636)
			(stroke
				(width 0.1524)
				(type default)
			)
			(layer "F.SilkS")
		)
		(fp_rect
			(start -1.524 0.7366)
			(end 1.524 -0.7366)
			(stroke
				(width 0)
				(type default)
			)
			(fill no)
			(layer "F.CrtYd")
		)
		(pad "1" smd rect
			(at 0.94996 0 180)
			(size 1.1176 1.3716)
			(layers "F.Cu" "F.Mask" "F.Paste")
			(net "RST_BTN_NODE1_C_L")
		)
		(pad "2" smd rect
			(at -0.94996 0 180)
			(size 1.1176 1.3716)
			(layers "F.Cu" "F.Mask" "F.Paste")
			(net "GND")
		)
	)
)
